(kicad_pcb
	(version 20260206)
	(generator "pcbnew")
	(generator_version "10.0")
	(general
		(thickness 1.6)
		(legacy_teardrops no)
	)
	(paper "A4")
	(title_block
		(title "03242023_DA0F0TMBIJ0_F0T_Motherboard_J_brd_V01_OCP.brd")
		(comment 1 "Grand Teton / footprint 1682 of 6105 (U1), pads 1928-2035 of 4677")
	)
	(layers
		(0 "F.Cu" signal "TOP")
		(4 "In1.Cu" signal "GND")
		(6 "In2.Cu" signal "IN1")
		(8 "In3.Cu" signal "GND1")
		(10 "In4.Cu" signal "IN2")
		(12 "In5.Cu" signal "GND2")
		(14 "In6.Cu" signal "IN3")
		(16 "In7.Cu" signal "GND3")
		(18 "In8.Cu" signal "VCC")
		(20 "In9.Cu" signal "VCC1")
		(22 "In10.Cu" signal "GND4")
		(24 "In11.Cu" signal "IN4")
		(26 "In12.Cu" signal "GND5")
		(28 "In13.Cu" signal "IN5")
		(30 "In14.Cu" signal "GND6")
		(32 "In15.Cu" signal "IN6")
		(34 "In16.Cu" signal "GND7")
		(2 "B.Cu" signal "BOTTOM")
		(9 "F.Adhes" user "F.Adhesive")
		(11 "B.Adhes" user "B.Adhesive")
		(13 "F.Paste" user "Package Geometry/Pastemask Top")
		(15 "B.Paste" user "Package Geometry/Pastemask Bottom")
		(5 "F.SilkS" user "Ref Des/Silkscreen Top")
		(7 "B.SilkS" user "Ref Des/Silkscreen Bottom")
		(1 "F.Mask" user "Board Geometry/Soldermask Top")
		(3 "B.Mask" user "Board Geometry/Soldermask Bottom")
		(17 "Dwgs.User" user "User.Drawings")
		(19 "Cmts.User" user "User.Comments")
		(21 "Eco1.User" user "User.Eco1")
		(23 "Eco2.User" user "User.Eco2")
		(25 "Edge.Cuts" user "Board Geometry/Outline")
		(27 "Margin" user)
		(31 "F.CrtYd" user "Package Geometry/Place Bound Top")
		(29 "B.CrtYd" user "Package Geometry/Place Bound Bottom")
		(35 "F.Fab" user "Ref Des/Assembly Top")
		(33 "B.Fab" user "Ref Des/Assembly Bottom")
	)
	(footprint ""
		(layer "F.Cu")
		(at 111.93018 -251.76988 90)
		(property "Reference" "U1"
			(at -74.913236 41.548812 0)
			(unlocked yes)
			(layer "F.SilkS")
			(effects
				(font
					(size 1.6002 1.1938)
					(thickness 0.1524)
				)
				(justify left)
			)
		)
		(property "Value" ""
			(at 0 0 90)
			(layer "F.Fab")
			(effects
				(font
					(size 1.27 1.27)
				)
			)
		)
		(duplicate_pad_numbers_are_jumpers no)
		(pad "CG68" smd circle
			(at 18.705576 4.049268 270)
			(size 0.4318 0.4318)
			(layers "F.Cu" "F.Mask" "F.Paste")
			(net "PVPP_HBM_CPU1")
		)
		(pad "CG70" smd circle
			(at 20.333462 4.049268 270)
			(size 0.4318 0.4318)
			(layers "F.Cu" "F.Mask" "F.Paste")
			(net "GND")
		)
		(pad "CG72" smd circle
			(at 21.961094 4.049268 270)
			(size 0.4318 0.4318)
			(layers "F.Cu" "F.Mask" "F.Paste")
			(net "GND")
		)
		(pad "CG74" smd circle
			(at 23.58898 4.049268 270)
			(size 0.4318 0.4318)
			(layers "F.Cu" "F.Mask" "F.Paste")
			(net "GND")
		)
		(pad "CG76" smd circle
			(at 25.216612 4.049268 270)
			(size 0.4318 0.4318)
			(layers "F.Cu" "F.Mask" "F.Paste")
			(net "Net_738")
		)
		(pad "CG78" smd circle
			(at 26.844498 4.049268 270)
			(size 0.4318 0.4318)
			(layers "F.Cu" "F.Mask" "F.Paste")
			(net "GND")
		)
		(pad "CG80" smd circle
			(at 28.472384 4.049268 270)
			(size 0.4318 0.4318)
			(layers "F.Cu" "F.Mask" "F.Paste")
			(net "PVCCIN_CPU1")
		)
		(pad "CG82" smd circle
			(at 30.100016 4.049268 270)
			(size 0.4318 0.4318)
			(layers "F.Cu" "F.Mask" "F.Paste")
			(net "PVCCIN_CPU1")
		)
		(pad "CG84" smd circle
			(at 31.727902 4.049268 270)
			(size 0.4318 0.4318)
			(layers "F.Cu" "F.Mask" "F.Paste")
			(net "PVCCIN_CPU1")
		)
		(pad "CG86" smd circle
			(at 33.355534 4.049268 270)
			(size 0.4318 0.4318)
			(layers "F.Cu" "F.Mask" "F.Paste")
			(net "PVCCIN_CPU1")
		)
		(pad "CG88" smd circle
			(at 34.98342 4.049268 270)
			(size 0.4318 0.4318)
			(layers "F.Cu" "F.Mask" "F.Paste")
			(net "PVCCIN_CPU1")
		)
		(pad "CG90" smd circle
			(at 36.611306 4.049268 270)
			(size 0.4318 0.4318)
			(layers "F.Cu" "F.Mask" "F.Paste")
			(net "PVCCIN_CPU1")
		)
		(pad "CH2" smd circle
			(at -36.611306 4.408932 270)
			(size 0.4318 0.4318)
			(layers "F.Cu" "F.Mask" "F.Paste")
			(net "UPI_CPU0_CPU1_P0P1_DN<20>")
		)
		(pad "CH4" smd circle
			(at -34.98342 4.408932 270)
			(size 0.4318 0.4318)
			(layers "F.Cu" "F.Mask" "F.Paste")
			(net "GND")
		)
		(pad "CH6" smd circle
			(at -33.355534 4.408932 270)
			(size 0.4318 0.4318)
			(layers "F.Cu" "F.Mask" "F.Paste")
			(net "UPI_CPU1_CPU0_P1P0_DN<19>")
		)
		(pad "CH8" smd circle
			(at -31.727902 4.408932 270)
			(size 0.4318 0.4318)
			(layers "F.Cu" "F.Mask" "F.Paste")
			(net "GND")
		)
		(pad "CH10" smd circle
			(at -30.100016 4.408932 270)
			(size 0.4318 0.4318)
			(layers "F.Cu" "F.Mask" "F.Paste")
			(net "P5E_CPU1_PE1_RX_DP<3>")
		)
		(pad "CH12" smd circle
			(at -28.472384 4.408932 270)
			(size 0.4318 0.4318)
			(layers "F.Cu" "F.Mask" "F.Paste")
			(net "GND")
		)
		(pad "CH14" smd circle
			(at -26.844498 4.408932 270)
			(size 0.4318 0.4318)
			(layers "F.Cu" "F.Mask" "F.Paste")
			(net "P5E_CPU1_PE1_TX_DP<3>")
		)
		(pad "CH16" smd circle
			(at -25.216612 4.408932 270)
			(size 0.4318 0.4318)
			(layers "F.Cu" "F.Mask" "F.Paste")
			(net "GND")
		)
		(pad "CH18" smd circle
			(at -23.58898 4.408932 270)
			(size 0.4318 0.4318)
			(layers "F.Cu" "F.Mask" "F.Paste")
			(net "TP_DMI_CPU1_PCH_TX_DP<5>")
		)
		(pad "CH20" smd circle
			(at -21.961094 4.408932 270)
			(size 0.4318 0.4318)
			(layers "F.Cu" "F.Mask" "F.Paste")
			(net "GND")
		)
		(pad "CH22" smd circle
			(at -20.333462 4.408932 270)
			(size 0.4318 0.4318)
			(layers "F.Cu" "F.Mask" "F.Paste")
			(net "PD_CPU1_ENH_MCECC_DIS")
		)
		(pad "CH24" smd circle
			(at -18.705576 4.408932 270)
			(size 0.4318 0.4318)
			(layers "F.Cu" "F.Mask" "F.Paste")
			(net "TP_H_SBLINK6_CPU1_PMSYNC")
		)
		(pad "CH26" smd circle
			(at -17.07769 4.408932 270)
			(size 0.4318 0.4318)
			(layers "F.Cu" "F.Mask" "F.Paste")
			(net "TP_H_SBLINK3_CPU1_PMSYNC")
		)
		(pad "CH61" smd circle
			(at 13.008356 4.518914 270)
			(size 0.4318 0.4318)
			(layers "F.Cu" "F.Mask" "F.Paste")
			(net "TP_CPU1_SPARE9")
		)
		(pad "CH63" smd circle
			(at 14.635988 4.518914 270)
			(size 0.4318 0.4318)
			(layers "F.Cu" "F.Mask" "F.Paste")
			(net "TP_SGPIO_S3M_CPU1_GSXDIN")
		)
		(pad "CH65" smd circle
			(at 16.263874 4.518914 270)
			(size 0.4318 0.4318)
			(layers "F.Cu" "F.Mask" "F.Paste")
			(net "PU_S3M_CPU1_CPLD_STATUS")
		)
		(pad "CH67" smd circle
			(at 17.89176 4.518914 270)
			(size 0.4318 0.4318)
			(layers "F.Cu" "F.Mask" "F.Paste")
			(net "GND")
		)
		(pad "CH69" smd circle
			(at 19.519392 4.518914 270)
			(size 0.4318 0.4318)
			(layers "F.Cu" "F.Mask" "F.Paste")
			(net "NC_CPU1_MDFI_DIE11_EW1")
		)
		(pad "CH71" smd circle
			(at 21.147278 4.518914 270)
			(size 0.4318 0.4318)
			(layers "F.Cu" "F.Mask" "F.Paste")
			(net "TP_PWRGD_S0_PWROK_CPU1_LVC1")
		)
		(pad "CH73" smd circle
			(at 22.77491 4.518914 270)
			(size 0.4318 0.4318)
			(layers "F.Cu" "F.Mask" "F.Paste")
			(net "GND")
		)
		(pad "CH75" smd circle
			(at 24.402796 4.518914 270)
			(size 0.4318 0.4318)
			(layers "F.Cu" "F.Mask" "F.Paste")
			(net "Net_712")
		)
		(pad "CH77" smd circle
			(at 26.030682 4.518914 270)
			(size 0.4318 0.4318)
			(layers "F.Cu" "F.Mask" "F.Paste")
			(net "Net_740")
		)
		(pad "CH79" smd circle
			(at 27.658314 4.518914 270)
			(size 0.4318 0.4318)
			(layers "F.Cu" "F.Mask" "F.Paste")
			(net "GND")
		)
		(pad "CH81" smd circle
			(at 29.2862 4.518914 270)
			(size 0.4318 0.4318)
			(layers "F.Cu" "F.Mask" "F.Paste")
			(net "PVCCIN_CPU1")
		)
		(pad "CH83" smd circle
			(at 30.914086 4.518914 270)
			(size 0.4318 0.4318)
			(layers "F.Cu" "F.Mask" "F.Paste")
			(net "GND")
		)
		(pad "CH85" smd circle
			(at 32.541718 4.518914 270)
			(size 0.4318 0.4318)
			(layers "F.Cu" "F.Mask" "F.Paste")
			(net "GND")
		)
		(pad "CH87" smd circle
			(at 34.169604 4.518914 270)
			(size 0.4318 0.4318)
			(layers "F.Cu" "F.Mask" "F.Paste")
			(net "GND")
		)
		(pad "CH89" smd circle
			(at 35.797236 4.518914 270)
			(size 0.4318 0.4318)
			(layers "F.Cu" "F.Mask" "F.Paste")
			(net "GND")
		)
		(pad "CH91" smd oval
			(at 37.425122 4.518914)
			(size 0.381 0.4826)
			(drill
				(offset 0 -0.0508)
			)
			(layers "F.Cu" "F.Mask" "F.Paste")
			(net "PVCCIN_CPU1")
		)
		(pad "CJ1" smd oval
			(at -37.425122 4.879086 180)
			(size 0.381 0.4826)
			(drill
				(offset 0 -0.0508)
			)
			(layers "F.Cu" "F.Mask" "F.Paste")
			(net "UPI_CPU0_CPU1_P0P1_DN<19>")
		)
		(pad "CJ3" smd circle
			(at -35.797236 4.879086 270)
			(size 0.4318 0.4318)
			(layers "F.Cu" "F.Mask" "F.Paste")
			(net "PVCCINFAON_CPU1")
		)
		(pad "CJ5" smd circle
			(at -34.169604 4.879086 270)
			(size 0.4318 0.4318)
			(layers "F.Cu" "F.Mask" "F.Paste")
			(net "UPI_CPU1_CPU0_P1P0_DN<18>")
		)
		(pad "CJ7" smd circle
			(at -32.541718 4.879086 270)
			(size 0.4318 0.4318)
			(layers "F.Cu" "F.Mask" "F.Paste")
			(net "PVCCINFAON_CPU1")
		)
		(pad "CJ9" smd circle
			(at -30.914086 4.879086 270)
			(size 0.4318 0.4318)
			(layers "F.Cu" "F.Mask" "F.Paste")
			(net "P5E_CPU1_PE1_RX_DP<2>")
		)
		(pad "CJ11" smd circle
			(at -29.2862 4.879086 270)
			(size 0.4318 0.4318)
			(layers "F.Cu" "F.Mask" "F.Paste")
			(net "PVCCINFAON_CPU1")
		)
		(pad "CJ13" smd circle
			(at -27.658314 4.879086 270)
			(size 0.4318 0.4318)
			(layers "F.Cu" "F.Mask" "F.Paste")
			(net "P5E_CPU1_PE1_TX_DN<3>")
		)
		(pad "CJ15" smd circle
			(at -26.030682 4.879086 270)
			(size 0.4318 0.4318)
			(layers "F.Cu" "F.Mask" "F.Paste")
			(net "PVCCINFAON_CPU1")
		)
		(pad "CJ17" smd circle
			(at -24.402796 4.879086 270)
			(size 0.4318 0.4318)
			(layers "F.Cu" "F.Mask" "F.Paste")
			(net "TP_DMI_CPU1_PCH_TX_DN<5>")
		)
		(pad "CJ19" smd circle
			(at -22.77491 4.879086 270)
			(size 0.4318 0.4318)
			(layers "F.Cu" "F.Mask" "F.Paste")
			(net "PVCCINFAON_CPU1")
		)
		(pad "CJ21" smd circle
			(at -21.147278 4.879086 270)
			(size 0.4318 0.4318)
			(layers "F.Cu" "F.Mask" "F.Paste")
			(net "TP_CPU1_IBL_GRST_WARN_CPU1_N")
		)
		(pad "CJ23" smd circle
			(at -19.519392 4.879086 270)
			(size 0.4318 0.4318)
			(layers "F.Cu" "F.Mask" "F.Paste")
			(net "TP_I2C_S3M_RTC_CPU1_SDA")
		)
		(pad "CJ25" smd circle
			(at -17.89176 4.879086 270)
			(size 0.4318 0.4318)
			(layers "F.Cu" "F.Mask" "F.Paste")
			(net "TP_I2C_S3M_RTC_CPU1_RST_N")
		)
		(pad "CJ60" smd circle
			(at 12.19454 4.989068 270)
			(size 0.4318 0.4318)
			(layers "F.Cu" "F.Mask" "F.Paste")
			(net "GND")
		)
		(pad "CJ62" smd circle
			(at 13.822426 4.989068 270)
			(size 0.4318 0.4318)
			(layers "F.Cu" "F.Mask" "F.Paste")
			(net "CPU1_RSVD<98>")
		)
		(pad "CJ64" smd circle
			(at 15.450058 4.989068 270)
			(size 0.4318 0.4318)
			(layers "F.Cu" "F.Mask" "F.Paste")
			(net "PU_S3M_CPU1_CPLD_CONFD")
		)
		(pad "CJ66" smd circle
			(at 17.07769 4.989068 270)
			(size 0.4318 0.4318)
			(layers "F.Cu" "F.Mask" "F.Paste")
			(net "TP_SGPIO_S3M_CPU1_GSXDLOAD")
		)
		(pad "CJ68" smd circle
			(at 18.705576 4.989068 270)
			(size 0.4318 0.4318)
			(layers "F.Cu" "F.Mask" "F.Paste")
			(net "NC_CPU1_MDFI_DIE11_NS0")
		)
		(pad "CJ70" smd circle
			(at 20.333462 4.989068 270)
			(size 0.4318 0.4318)
			(layers "F.Cu" "F.Mask" "F.Paste")
			(net "NC_CPU1_MDFI_DIE11_EW0")
		)
		(pad "CJ72" smd circle
			(at 21.961094 4.989068 270)
			(size 0.4318 0.4318)
			(layers "F.Cu" "F.Mask" "F.Paste")
			(net "PUD_XTAL_CPU1_MODE1")
		)
		(pad "CJ74" smd circle
			(at 23.58898 4.989068 270)
			(size 0.4318 0.4318)
			(layers "F.Cu" "F.Mask" "F.Paste")
			(net "Net_735")
		)
		(pad "CJ76" smd circle
			(at 25.216612 4.989068 270)
			(size 0.4318 0.4318)
			(layers "F.Cu" "F.Mask" "F.Paste")
			(net "GND")
		)
		(pad "CJ78" smd circle
			(at 26.844498 4.989068 270)
			(size 0.4318 0.4318)
			(layers "F.Cu" "F.Mask" "F.Paste")
			(net "Net_716")
		)
		(pad "CJ80" smd circle
			(at 28.472384 4.989068 270)
			(size 0.4318 0.4318)
			(layers "F.Cu" "F.Mask" "F.Paste")
			(net "GND")
		)
		(pad "CJ82" smd circle
			(at 30.100016 4.989068 270)
			(size 0.4318 0.4318)
			(layers "F.Cu" "F.Mask" "F.Paste")
			(net "PVCCIN_CPU1")
		)
		(pad "CJ84" smd circle
			(at 31.727902 4.989068 270)
			(size 0.4318 0.4318)
			(layers "F.Cu" "F.Mask" "F.Paste")
			(net "PVCCIN_CPU1")
		)
		(pad "CJ86" smd circle
			(at 33.355534 4.989068 270)
			(size 0.4318 0.4318)
			(layers "F.Cu" "F.Mask" "F.Paste")
			(net "PVCCIN_CPU1")
		)
		(pad "CJ88" smd circle
			(at 34.98342 4.989068 270)
			(size 0.4318 0.4318)
			(layers "F.Cu" "F.Mask" "F.Paste")
			(net "PVCCIN_CPU1")
		)
		(pad "CJ90" smd circle
			(at 36.611306 4.989068 270)
			(size 0.4318 0.4318)
			(layers "F.Cu" "F.Mask" "F.Paste")
			(net "PVCCIN_CPU1")
		)
		(pad "CK2" smd circle
			(at -36.611306 5.348732 270)
			(size 0.4318 0.4318)
			(layers "F.Cu" "F.Mask" "F.Paste")
			(net "UPI_CPU0_CPU1_P0P1_DP<19>")
		)
		(pad "CK4" smd circle
			(at -34.98342 5.348732 270)
			(size 0.4318 0.4318)
			(layers "F.Cu" "F.Mask" "F.Paste")
			(net "GND")
		)
		(pad "CK6" smd circle
			(at -33.355534 5.348732 270)
			(size 0.4318 0.4318)
			(layers "F.Cu" "F.Mask" "F.Paste")
			(net "UPI_CPU1_CPU0_P1P0_DP<18>")
		)
		(pad "CK8" smd circle
			(at -31.727902 5.348732 270)
			(size 0.4318 0.4318)
			(layers "F.Cu" "F.Mask" "F.Paste")
			(net "GND")
		)
		(pad "CK10" smd circle
			(at -30.100016 5.348732 270)
			(size 0.4318 0.4318)
			(layers "F.Cu" "F.Mask" "F.Paste")
			(net "P5E_CPU1_PE1_RX_DN<2>")
		)
		(pad "CK12" smd circle
			(at -28.472384 5.348732 270)
			(size 0.4318 0.4318)
			(layers "F.Cu" "F.Mask" "F.Paste")
			(net "GND")
		)
		(pad "CK14" smd circle
			(at -26.844498 5.348732 270)
			(size 0.4318 0.4318)
			(layers "F.Cu" "F.Mask" "F.Paste")
			(net "P5E_CPU1_PE1_TX_DN<2>")
		)
		(pad "CK16" smd circle
			(at -25.216612 5.348732 270)
			(size 0.4318 0.4318)
			(layers "F.Cu" "F.Mask" "F.Paste")
			(net "GND")
		)
		(pad "CK18" smd circle
			(at -23.58898 5.348732 270)
			(size 0.4318 0.4318)
			(layers "F.Cu" "F.Mask" "F.Paste")
			(net "TP_DMI_CPU1_PCH_TX_DN<6>")
		)
		(pad "CK20" smd circle
			(at -21.961094 5.348732 270)
			(size 0.4318 0.4318)
			(layers "F.Cu" "F.Mask" "F.Paste")
			(net "GND")
		)
		(pad "CK22" smd circle
			(at -20.333462 5.348732 270)
			(size 0.4318 0.4318)
			(layers "F.Cu" "F.Mask" "F.Paste")
			(net "TP_FM_SYS_RST_CPU1_N")
		)
		(pad "CK24" smd circle
			(at -18.705576 5.348732 270)
			(size 0.4318 0.4318)
			(layers "F.Cu" "F.Mask" "F.Paste")
			(net "TP_FM_IBL_PWRBTN_CPU1_N")
		)
		(pad "CK26" smd circle
			(at -17.07769 5.348732 270)
			(size 0.4318 0.4318)
			(layers "F.Cu" "F.Mask" "F.Paste")
			(net "GND")
		)
		(pad "CK61" smd circle
			(at 13.008356 5.458714 270)
			(size 0.4318 0.4318)
			(layers "F.Cu" "F.Mask" "F.Paste")
			(net "TP_CPU1_SPARE8")
		)
		(pad "CK63" smd circle
			(at 14.635988 5.458714 270)
			(size 0.4318 0.4318)
			(layers "F.Cu" "F.Mask" "F.Paste")
			(net "GND")
		)
		(pad "CK65" smd circle
			(at 16.263874 5.458714 270)
			(size 0.4318 0.4318)
			(layers "F.Cu" "F.Mask" "F.Paste")
			(net "FM_S3M_CPU1_CPLD_CONFIG_N")
		)
		(pad "CK67" smd circle
			(at 17.89176 5.458714 270)
			(size 0.4318 0.4318)
			(layers "F.Cu" "F.Mask" "F.Paste")
			(net "NC_CPU1_MDFI_DIE11_NS1")
		)
		(pad "CK69" smd circle
			(at 19.519392 5.458714 270)
			(size 0.4318 0.4318)
			(layers "F.Cu" "F.Mask" "F.Paste")
			(net "GND")
		)
		(pad "CK71" smd circle
			(at 21.147278 5.458714 270)
			(size 0.4318 0.4318)
			(layers "F.Cu" "F.Mask" "F.Paste")
			(net "PU_CPU1_UPI3_AC_COUPLING")
		)
		(pad "CK73" smd circle
			(at 22.77491 5.458714 270)
			(size 0.4318 0.4318)
			(layers "F.Cu" "F.Mask" "F.Paste")
			(net "PVCCFA_EHV_FIVRA_CPU1")
		)
		(pad "CK75" smd circle
			(at 24.402796 5.458714 270)
			(size 0.4318 0.4318)
			(layers "F.Cu" "F.Mask" "F.Paste")
			(net "Net_711")
		)
		(pad "CK77" smd circle
			(at 26.030682 5.458714 270)
			(size 0.4318 0.4318)
			(layers "F.Cu" "F.Mask" "F.Paste")
			(net "Net_741")
		)
		(pad "CK79" smd circle
			(at 27.658314 5.458714 270)
			(size 0.4318 0.4318)
			(layers "F.Cu" "F.Mask" "F.Paste")
			(net "PVCCFA_EHV_FIVRA_CPU1")
		)
		(pad "CK81" smd circle
			(at 29.2862 5.458714 270)
			(size 0.4318 0.4318)
			(layers "F.Cu" "F.Mask" "F.Paste")
			(net "GND")
		)
		(pad "CK83" smd circle
			(at 30.914086 5.458714 270)
			(size 0.4318 0.4318)
			(layers "F.Cu" "F.Mask" "F.Paste")
			(net "PVCCIN_CPU1")
		)
		(pad "CK85" smd circle
			(at 32.541718 5.458714 270)
			(size 0.4318 0.4318)
			(layers "F.Cu" "F.Mask" "F.Paste")
			(net "PVCCIN_CPU1")
		)
		(pad "CK87" smd circle
			(at 34.169604 5.458714 270)
			(size 0.4318 0.4318)
			(layers "F.Cu" "F.Mask" "F.Paste")
			(net "PVCCIN_CPU1")
		)
		(pad "CK89" smd circle
			(at 35.797236 5.458714 270)
			(size 0.4318 0.4318)
			(layers "F.Cu" "F.Mask" "F.Paste")
			(net "PVCCIN_CPU1")
		)
		(pad "CK91" smd oval
			(at 37.425122 5.458714)
			(size 0.381 0.4826)
			(drill
				(offset 0 -0.0508)
			)
			(layers "F.Cu" "F.Mask" "F.Paste")
			(net "PVCCIN_CPU1")
		)
		(pad "CL1" smd oval
			(at -37.425122 5.818886 180)
			(size 0.381 0.4826)
			(drill
				(offset 0 -0.0508)
			)
			(layers "F.Cu" "F.Mask" "F.Paste")
			(net "GND")
		)
		(pad "CL3" smd circle
			(at -35.797236 5.818886 270)
			(size 0.4318 0.4318)
			(layers "F.Cu" "F.Mask" "F.Paste")
			(net "UPI_CPU0_CPU1_P0P1_DN<18>")
		)
		(pad "CL5" smd circle
			(at -34.169604 5.818886 270)
			(size 0.4318 0.4318)
			(layers "F.Cu" "F.Mask" "F.Paste")
			(net "GND")
		)
		(pad "CL7" smd circle
			(at -32.541718 5.818886 270)
			(size 0.4318 0.4318)
			(layers "F.Cu" "F.Mask" "F.Paste")
			(net "UPI_CPU1_CPU0_P1P0_DP<17>")
		)
		(pad "CL9" smd circle
			(at -30.914086 5.818886 270)
			(size 0.4318 0.4318)
			(layers "F.Cu" "F.Mask" "F.Paste")
			(net "GND")
		)
		(pad "CL11" smd circle
			(at -29.2862 5.818886 270)
			(size 0.4318 0.4318)
			(layers "F.Cu" "F.Mask" "F.Paste")
			(net "P5E_CPU1_PE1_RX_DN<1>")
		)
		(pad "CL13" smd circle
			(at -27.658314 5.818886 270)
			(size 0.4318 0.4318)
			(layers "F.Cu" "F.Mask" "F.Paste")
			(net "GND")
		)
		(pad "CL15" smd circle
			(at -26.030682 5.818886 270)
			(size 0.4318 0.4318)
			(layers "F.Cu" "F.Mask" "F.Paste")
			(net "P5E_CPU1_PE1_TX_DP<2>")
		)
		(pad "CL17" smd circle
			(at -24.402796 5.818886 270)
			(size 0.4318 0.4318)
			(layers "F.Cu" "F.Mask" "F.Paste")
			(net "GND")
		)
	)
)
